FILE_TYPE = CONNECTIVITY;
{Allegro Design Entry HDL 17.2-2016 S081 (4005846) 1/11/2022}
"PAGE_NUMBER" = 56;
0"NC";
1"M_F_CPU1_SA_CA<6:0>";
2"M_F_CPU1_SA_CS_N<3:0>";
3"M_F_CPU1_SA_DQS_DN<9:0>";
4"M_F_CPU1_SA_DQS_DP<9:0>";
5"M_F_CPU1_SB_CA<6:0>";
6"M_F_CPU1_SB_CS_N<3:0>";
7"M_F_CPU1_SB_DQS_DN<9:0>";
8"M_F_CPU1_SB_DQS_DP<9:0>";
9"M_F_CPU1_SB_CB<7:0>";
10"M_F_CPU1_SB_DQ<31:0>";
11"M_F_CPU1_SA_CB<7:0>";
12"M_F_CPU1_SA_DQ<31:0>";
13"M_F_CPU1_CLK_DP<1:0>";
14"M_F_CPU1_CLK_DN<1:0>";
15"M_F_CPU1_SB_DQ<11>";
16"M_F_CPU1_SA_CB<7>";
17"M_F_CPU1_SA_DQ<0>";
18"M_F_CPU1_SA_DQ<1>";
19"M_F_CPU1_SA_DQ<2>";
20"M_F_CPU1_CLK_DN<1>";
21"M_F_CPU1_CLK_DN<0>";
22"M_F_CPU1_CLK_DP<1>";
23"M_F_CPU1_CLK_DP<0>";
24"M_F_CPU1_SA_DQ<31>";
25"M_F_CPU1_SA_DQ<30>";
26"M_F_CPU1_SA_DQ<29>";
27"M_F_CPU1_SA_DQ<28>";
28"M_F_CPU1_SA_DQ<27>";
29"M_F_CPU1_SA_DQ<26>";
30"M_F_CPU1_SA_DQ<25>";
31"M_F_CPU1_SA_DQ<24>";
32"M_F_CPU1_SA_DQ<23>";
33"M_F_CPU1_SA_DQ<22>";
34"M_F_CPU1_SA_DQ<21>";
35"M_F_CPU1_SA_DQ<20>";
36"M_F_CPU1_SA_DQ<19>";
37"M_F_CPU1_SA_DQ<18>";
38"M_F_CPU1_SA_DQ<17>";
39"M_F_CPU1_SA_DQ<16>";
40"M_F_CPU1_SA_DQ<15>";
41"M_F_CPU1_SA_DQ<14>";
42"M_F_CPU1_SA_DQ<13>";
43"M_F_CPU1_SA_DQ<12>";
44"M_F_CPU1_SA_DQ<11>";
45"M_F_CPU1_SA_DQ<10>";
46"M_F_CPU1_SA_DQ<9>";
47"M_F_CPU1_SA_DQ<8>";
48"M_F_CPU1_SA_DQ<7>";
49"M_F_CPU1_SA_DQ<6>";
50"M_F_CPU1_SA_DQ<5>";
51"M_F_CPU1_SA_DQ<4>";
52"M_F_CPU1_SA_DQ<3>";
53"M_F_CPU1_SA_CB<6>";
54"M_F_CPU1_SA_CB<5>";
55"M_F_CPU1_SA_CB<4>";
56"M_F_CPU1_SA_CB<3>";
57"M_F_CPU1_SA_CB<2>";
58"M_F_CPU1_SA_CB<1>";
59"M_F_CPU1_SA_CB<0>";
60"M_F_CPU1_SB_DQ<31>";
61"M_F_CPU1_SB_DQ<30>";
62"M_F_CPU1_SB_DQ<29>";
63"M_F_CPU1_SB_DQ<28>";
64"M_F_CPU1_SB_DQ<27>";
65"M_F_CPU1_SB_DQ<26>";
66"M_F_CPU1_SB_DQ<25>";
67"M_F_CPU1_SB_DQ<24>";
68"M_F_CPU1_SB_DQ<23>";
69"M_F_CPU1_SB_DQ<22>";
70"M_F_CPU1_SB_DQ<21>";
71"M_F_CPU1_SB_DQ<20>";
72"M_F_CPU1_SB_DQ<19>";
73"M_F_CPU1_SB_DQ<18>";
74"M_F_CPU1_SB_DQ<17>";
75"M_F_CPU1_SB_DQ<16>";
76"M_F_CPU1_SB_DQ<15>";
77"M_F_CPU1_SB_DQ<14>";
78"M_F_CPU1_SB_DQ<13>";
79"M_F_CPU1_SB_DQ<12>";
80"M_F_CPU1_SB_DQ<10>";
81"M_F_CPU1_SB_DQ<9>";
82"M_F_CPU1_SB_DQ<8>";
83"M_F_CPU1_SB_DQ<7>";
84"M_F_CPU1_SB_DQ<6>";
85"M_F_CPU1_SB_DQ<5>";
86"M_F_CPU1_SB_DQ<4>";
87"M_F_CPU1_SB_DQ<3>";
88"M_F_CPU1_SB_DQ<2>";
89"M_F_CPU1_SB_DQ<1>";
90"M_F_CPU1_SB_DQ<0>";
91"M_F_CPU1_SB_CB<7>";
92"M_F_CPU1_SB_CB<6>";
93"M_F_CPU1_SB_CB<5>";
94"M_F_CPU1_SB_CB<4>";
95"M_F_CPU1_SB_CB<3>";
96"M_F_CPU1_SB_CB<2>";
97"M_F_CPU1_SB_CB<1>";
98"M_F_CPU1_SB_CB<0>";
99"M_F_CPU1_SB_PAR";
100"M_F_CPU1_SB_DQS_DP<0>";
101"M_F_CPU1_SB_DQS_DP<1>";
102"M_F_CPU1_SB_DQS_DP<2>";
103"M_F_CPU1_SB_DQS_DP<3>";
104"M_F_CPU1_SB_DQS_DP<4>";
105"M_F_CPU1_SB_DQS_DP<5>";
106"M_F_CPU1_SB_DQS_DP<6>";
107"M_F_CPU1_SB_DQS_DP<7>";
108"M_F_CPU1_SB_DQS_DP<8>";
109"M_F_CPU1_SB_DQS_DP<9>";
110"M_F_CPU1_SB_DQS_DN<0>";
111"M_F_CPU1_SB_DQS_DN<1>";
112"M_F_CPU1_SB_DQS_DN<2>";
113"M_F_CPU1_SB_DQS_DN<3>";
114"M_F_CPU1_SB_DQS_DN<4>";
115"M_F_CPU1_SB_DQS_DN<5>";
116"M_F_CPU1_SB_DQS_DN<6>";
117"M_F_CPU1_SB_DQS_DN<7>";
118"M_F_CPU1_SB_DQS_DN<8>";
119"M_F_CPU1_SB_DQS_DN<9>";
120"M_F_CPU1_SB_CS_N<0>";
121"M_F_CPU1_SB_CS_N<1>";
122"M_F_CPU1_SB_CS_N<2>";
123"M_F_CPU1_SB_CS_N<3>";
124"M_F_CPU1_SB_CA<0>";
125"M_F_CPU1_SB_CA<1>";
126"M_F_CPU1_SB_CA<2>";
127"M_F_CPU1_SB_CA<3>";
128"M_F_CPU1_SB_CA<4>";
129"M_F_CPU1_SB_CA<5>";
130"M_F_CPU1_SB_CA<6>";
131"M_F_CPU1_SA_PAR";
132"M_F_CPU1_SA_DQS_DP<0>";
133"M_F_CPU1_SA_DQS_DP<1>";
134"M_F_CPU1_SA_DQS_DP<2>";
135"M_F_CPU1_SA_DQS_DP<3>";
136"M_F_CPU1_SA_DQS_DP<4>";
137"M_F_CPU1_SA_DQS_DP<5>";
138"M_F_CPU1_SA_DQS_DP<6>";
139"M_F_CPU1_SA_DQS_DP<7>";
140"M_F_CPU1_SA_DQS_DP<8>";
141"M_F_CPU1_SA_DQS_DP<9>";
142"M_F_CPU1_SA_DQS_DN<0>";
143"M_F_CPU1_SA_DQS_DN<1>";
144"M_F_CPU1_SA_DQS_DN<2>";
145"M_F_CPU1_SA_DQS_DN<3>";
146"M_F_CPU1_SA_DQS_DN<4>";
147"M_F_CPU1_SA_DQS_DN<5>";
148"M_F_CPU1_SA_DQS_DN<6>";
149"M_F_CPU1_SA_DQS_DN<7>";
150"M_F_CPU1_SA_DQS_DN<8>";
151"M_F_CPU1_SA_DQS_DN<9>";
152"M_F_CPU1_SA_CS_N<0>";
153"M_F_CPU1_SA_CS_N<1>";
154"M_F_CPU1_SA_CS_N<2>";
155"M_F_CPU1_SA_CS_N<3>";
156"M_F_CPU1_SA_CA<0>";
157"M_F_CPU1_SA_CA<1>";
158"M_F_CPU1_SA_CA<2>";
159"M_F_CPU1_SA_CA<3>";
160"M_F_CPU1_SA_CA<4>";
161"M_F_CPU1_SA_CA<5>";
162"M_F_CPU1_SA_CA<6>";
163"M_F_CPU1_SB_RSP<0>";
164"M_F_CPU1_SB_RSP<1>";
165"M_F_CPU1_SA_RSP<0>";
166"M_F_CPU1_SA_RSP<1>";
167"M_F_CPU1_ALERT_N";
%"TAP"
"1","(2450,625)","0","standard","I100";
;
CDS_LIB"standard"
BODY_TYPE"PLUMBING"
HDL_TAP"TRUE";
"B \NAC \NWC"2;
"S \NAC"
BN"1"153;
%"TAP"
"1","(2450,675)","0","standard","I101";
;
CDS_LIB"standard"
BODY_TYPE"PLUMBING"
HDL_TAP"TRUE";
"B \NAC \NWC"2;
"S \NAC"
BN"2"154;
%"TAP"
"1","(2450,575)","0","standard","I102";
;
CDS_LIB"standard"
BODY_TYPE"PLUMBING"
HDL_TAP"TRUE";
"B \NAC \NWC"2;
"S \NAC"
BN"0"152;
%"TAP"
"1","(2450,725)","0","standard","I103";
;
CDS_LIB"standard"
BODY_TYPE"PLUMBING"
HDL_TAP"TRUE";
"B \NAC \NWC"2;
"S \NAC"
BN"3"155;
%"TAP"
"1","(2450,925)","0","standard","I104";
;
CDS_LIB"standard"
BODY_TYPE"PLUMBING"
HDL_TAP"TRUE";
"B \NAC \NWC"5;
"S \NAC"
BN"0"124;
%"TAP"
"1","(2450,1025)","0","standard","I105";
;
CDS_LIB"standard"
BODY_TYPE"PLUMBING"
HDL_TAP"TRUE";
"B \NAC \NWC"5;
"S \NAC"
BN"2"126;
%"TAP"
"1","(2450,975)","0","standard","I106";
;
CDS_LIB"standard"
BODY_TYPE"PLUMBING"
HDL_TAP"TRUE";
"B \NAC \NWC"5;
"S \NAC"
BN"1"125;
%"TAP"
"1","(2450,1175)","0","standard","I107";
;
CDS_LIB"standard"
BODY_TYPE"PLUMBING"
HDL_TAP"TRUE";
"B \NAC \NWC"5;
"S \NAC"
BN"5"129;
%"TAP"
"1","(2450,1075)","0","standard","I108";
;
CDS_LIB"standard"
BODY_TYPE"PLUMBING"
HDL_TAP"TRUE";
"B \NAC \NWC"5;
"S \NAC"
BN"3"127;
%"TAP"
"1","(2450,1125)","0","standard","I109";
;
CDS_LIB"standard"
BODY_TYPE"PLUMBING"
HDL_TAP"TRUE";
"B \NAC \NWC"5;
"S \NAC"
BN"4"128;
%"TAP"
"1","(2450,1225)","0","standard","I110";
;
CDS_LIB"standard"
BODY_TYPE"PLUMBING"
HDL_TAP"TRUE";
"B \NAC \NWC"5;
"S \NAC"
BN"6"130;
%"TAP"
"1","(2450,1425)","0","standard","I111";
;
CDS_LIB"standard"
BODY_TYPE"PLUMBING"
HDL_TAP"TRUE";
"B \NAC \NWC"1;
"S \NAC"
BN"0"156;
%"TAP"
"1","(2450,1525)","0","standard","I112";
;
CDS_LIB"standard"
BODY_TYPE"PLUMBING"
HDL_TAP"TRUE";
"B \NAC \NWC"1;
"S \NAC"
BN"2"158;
%"TAP"
"1","(2450,1475)","0","standard","I113";
;
CDS_LIB"standard"
BODY_TYPE"PLUMBING"
HDL_TAP"TRUE";
"B \NAC \NWC"1;
"S \NAC"
BN"1"157;
%"TAP"
"1","(2450,1575)","0","standard","I114";
;
CDS_LIB"standard"
BODY_TYPE"PLUMBING"
HDL_TAP"TRUE";
"B \NAC \NWC"1;
"S \NAC"
BN"3"159;
%"TAP"
"1","(2450,1675)","0","standard","I115";
;
CDS_LIB"standard"
BODY_TYPE"PLUMBING"
HDL_TAP"TRUE";
"B \NAC \NWC"1;
"S \NAC"
BN"5"161;
%"TAP"
"1","(2450,1625)","0","standard","I116";
;
CDS_LIB"standard"
BODY_TYPE"PLUMBING"
HDL_TAP"TRUE";
"B \NAC \NWC"1;
"S \NAC"
BN"4"160;
%"TAP"
"1","(2450,1725)","0","standard","I117";
;
CDS_LIB"standard"
BODY_TYPE"PLUMBING"
HDL_TAP"TRUE";
"B \NAC \NWC"1;
"S \NAC"
BN"6"162;
%"TAP"
"1","(2450,1875)","0","standard","I118";
;
CDS_LIB"standard"
BODY_TYPE"PLUMBING"
HDL_TAP"TRUE";
"B \NAC \NWC"7;
"S \NAC"
BN"0"110;
%"TAP"
"1","(2450,1925)","0","standard","I119";
;
CDS_LIB"standard"
BODY_TYPE"PLUMBING"
HDL_TAP"TRUE";
"B \NAC \NWC"7;
"S \NAC"
BN"1"111;
%"TAP"
"1","(-975,275)","2","standard","I12";
;
CDS_LIB"standard"
BODY_TYPE"PLUMBING"
HDL_TAP"TRUE";
"B \NAC \NWC"9;
"S \NAC"
BN"4"94;
%"TAP"
"1","(2450,1975)","0","standard","I120";
;
CDS_LIB"standard"
BODY_TYPE"PLUMBING"
HDL_TAP"TRUE";
"B \NAC \NWC"7;
"S \NAC"
BN"2"112;
%"TAP"
"1","(2450,2025)","0","standard","I121";
;
CDS_LIB"standard"
BODY_TYPE"PLUMBING"
HDL_TAP"TRUE";
"B \NAC \NWC"7;
"S \NAC"
BN"3"113;
%"TAP"
"1","(2450,2075)","0","standard","I122";
;
CDS_LIB"standard"
BODY_TYPE"PLUMBING"
HDL_TAP"TRUE";
"B \NAC \NWC"7;
"S \NAC"
BN"4"114;
%"TAP"
"1","(2450,2175)","0","standard","I123";
;
CDS_LIB"standard"
BODY_TYPE"PLUMBING"
HDL_TAP"TRUE";
"B \NAC \NWC"7;
"S \NAC"
BN"6"116;
%"TAP"
"1","(2450,2125)","0","standard","I124";
;
CDS_LIB"standard"
BODY_TYPE"PLUMBING"
HDL_TAP"TRUE";
"B \NAC \NWC"7;
"S \NAC"
BN"5"115;
%"TAP"
"1","(2450,2325)","0","standard","I125";
;
CDS_LIB"standard"
BODY_TYPE"PLUMBING"
HDL_TAP"TRUE";
"B \NAC \NWC"7;
"S \NAC"
BN"9"119;
%"TAP"
"1","(2450,2275)","0","standard","I126";
;
CDS_LIB"standard"
BODY_TYPE"PLUMBING"
HDL_TAP"TRUE";
"B \NAC \NWC"7;
"S \NAC"
BN"8"118;
%"TAP"
"1","(2450,2225)","0","standard","I127";
;
CDS_LIB"standard"
BODY_TYPE"PLUMBING"
HDL_TAP"TRUE";
"B \NAC \NWC"7;
"S \NAC"
BN"7"117;
%"TAP"
"1","(2450,2425)","0","standard","I128";
;
CDS_LIB"standard"
BODY_TYPE"PLUMBING"
HDL_TAP"TRUE";
"B \NAC \NWC"8;
"S \NAC"
BN"0"100;
%"TAP"
"1","(2450,2475)","0","standard","I129";
;
CDS_LIB"standard"
BODY_TYPE"PLUMBING"
HDL_TAP"TRUE";
"B \NAC \NWC"8;
"S \NAC"
BN"1"101;
%"TAP"
"1","(-975,225)","2","standard","I13";
;
CDS_LIB"standard"
BODY_TYPE"PLUMBING"
HDL_TAP"TRUE";
"B \NAC \NWC"9;
"S \NAC"
BN"3"95;
%"TAP"
"1","(2450,2525)","0","standard","I130";
;
CDS_LIB"standard"
BODY_TYPE"PLUMBING"
HDL_TAP"TRUE";
"B \NAC \NWC"8;
"S \NAC"
BN"2"102;
%"TAP"
"1","(2450,2575)","0","standard","I131";
;
CDS_LIB"standard"
BODY_TYPE"PLUMBING"
HDL_TAP"TRUE";
"B \NAC \NWC"8;
"S \NAC"
BN"3"103;
%"TAP"
"1","(2450,2725)","0","standard","I132";
;
CDS_LIB"standard"
BODY_TYPE"PLUMBING"
HDL_TAP"TRUE";
"B \NAC \NWC"8;
"S \NAC"
BN"6"106;
%"TAP"
"1","(2450,2625)","0","standard","I133";
;
CDS_LIB"standard"
BODY_TYPE"PLUMBING"
HDL_TAP"TRUE";
"B \NAC \NWC"8;
"S \NAC"
BN"4"104;
%"TAP"
"1","(2450,2675)","0","standard","I134";
;
CDS_LIB"standard"
BODY_TYPE"PLUMBING"
HDL_TAP"TRUE";
"B \NAC \NWC"8;
"S \NAC"
BN"5"105;
%"TAP"
"1","(2450,2825)","0","standard","I135";
;
CDS_LIB"standard"
BODY_TYPE"PLUMBING"
HDL_TAP"TRUE";
"B \NAC \NWC"8;
"S \NAC"
BN"8"108;
%"TAP"
"1","(2450,2875)","0","standard","I136";
;
CDS_LIB"standard"
BODY_TYPE"PLUMBING"
HDL_TAP"TRUE";
"B \NAC \NWC"8;
"S \NAC"
BN"9"109;
%"TAP"
"1","(2450,2775)","0","standard","I137";
;
CDS_LIB"standard"
BODY_TYPE"PLUMBING"
HDL_TAP"TRUE";
"B \NAC \NWC"8;
"S \NAC"
BN"7"107;
%"TAP"
"1","(2450,3075)","0","standard","I138";
;
CDS_LIB"standard"
BODY_TYPE"PLUMBING"
HDL_TAP"TRUE";
"B \NAC \NWC"3;
"S \NAC"
BN"1"143;
%"TAP"
"1","(2450,3025)","0","standard","I139";
;
CDS_LIB"standard"
BODY_TYPE"PLUMBING"
HDL_TAP"TRUE";
"B \NAC \NWC"3;
"S \NAC"
BN"0"142;
%"TAP"
"1","(-975,375)","2","standard","I14";
;
CDS_LIB"standard"
BODY_TYPE"PLUMBING"
HDL_TAP"TRUE";
"B \NAC \NWC"9;
"S \NAC"
BN"6"92;
%"TAP"
"1","(2450,3225)","0","standard","I140";
;
CDS_LIB"standard"
BODY_TYPE"PLUMBING"
HDL_TAP"TRUE";
"B \NAC \NWC"3;
"S \NAC"
BN"4"146;
%"TAP"
"1","(2450,3125)","0","standard","I141";
;
CDS_LIB"standard"
BODY_TYPE"PLUMBING"
HDL_TAP"TRUE";
"B \NAC \NWC"3;
"S \NAC"
BN"2"144;
%"TAP"
"1","(2450,3175)","0","standard","I142";
;
CDS_LIB"standard"
BODY_TYPE"PLUMBING"
HDL_TAP"TRUE";
"B \NAC \NWC"3;
"S \NAC"
BN"3"145;
%"TAP"
"1","(2450,3275)","0","standard","I143";
;
CDS_LIB"standard"
BODY_TYPE"PLUMBING"
HDL_TAP"TRUE";
"B \NAC \NWC"3;
"S \NAC"
BN"5"147;
%"TAP"
"1","(2450,3325)","0","standard","I144";
;
CDS_LIB"standard"
BODY_TYPE"PLUMBING"
HDL_TAP"TRUE";
"B \NAC \NWC"3;
"S \NAC"
BN"6"148;
%"TAP"
"1","(2450,3375)","0","standard","I145";
;
CDS_LIB"standard"
BODY_TYPE"PLUMBING"
HDL_TAP"TRUE";
"B \NAC \NWC"3;
"S \NAC"
BN"7"149;
%"TAP"
"1","(2450,3475)","0","standard","I146";
;
CDS_LIB"standard"
BODY_TYPE"PLUMBING"
HDL_TAP"TRUE";
"B \NAC \NWC"3;
"S \NAC"
BN"9"151;
%"TAP"
"1","(2450,3425)","0","standard","I147";
;
CDS_LIB"standard"
BODY_TYPE"PLUMBING"
HDL_TAP"TRUE";
"B \NAC \NWC"3;
"S \NAC"
BN"8"150;
%"TAP"
"1","(2450,3575)","0","standard","I148";
;
CDS_LIB"standard"
BODY_TYPE"PLUMBING"
HDL_TAP"TRUE";
"B \NAC \NWC"4;
"S \NAC"
BN"0"132;
%"TAP"
"1","(2450,3625)","0","standard","I149";
;
CDS_LIB"standard"
BODY_TYPE"PLUMBING"
HDL_TAP"TRUE";
"B \NAC \NWC"4;
"S \NAC"
BN"1"133;
%"TAP"
"1","(-975,325)","2","standard","I15";
;
CDS_LIB"standard"
BODY_TYPE"PLUMBING"
HDL_TAP"TRUE";
"B \NAC \NWC"9;
"S \NAC"
BN"5"93;
%"TAP"
"1","(2450,3725)","0","standard","I150";
;
CDS_LIB"standard"
BODY_TYPE"PLUMBING"
HDL_TAP"TRUE";
"B \NAC \NWC"4;
"S \NAC"
BN"3"135;
%"TAP"
"1","(2450,3675)","0","standard","I151";
;
CDS_LIB"standard"
BODY_TYPE"PLUMBING"
HDL_TAP"TRUE";
"B \NAC \NWC"4;
"S \NAC"
BN"2"134;
%"TAP"
"1","(2450,3775)","0","standard","I152";
;
CDS_LIB"standard"
BODY_TYPE"PLUMBING"
HDL_TAP"TRUE";
"B \NAC \NWC"4;
"S \NAC"
BN"4"136;
%"TAP"
"1","(2450,3825)","0","standard","I153";
;
CDS_LIB"standard"
BODY_TYPE"PLUMBING"
HDL_TAP"TRUE";
"B \NAC \NWC"4;
"S \NAC"
BN"5"137;
%"TAP"
"1","(2450,3875)","0","standard","I154";
;
CDS_LIB"standard"
BODY_TYPE"PLUMBING"
HDL_TAP"TRUE";
"B \NAC \NWC"4;
"S \NAC"
BN"6"138;
%"TAP"
"1","(2450,3975)","0","standard","I155";
;
CDS_LIB"standard"
BODY_TYPE"PLUMBING"
HDL_TAP"TRUE";
"B \NAC \NWC"4;
"S \NAC"
BN"8"140;
%"TAP"
"1","(2450,3925)","0","standard","I156";
;
CDS_LIB"standard"
BODY_TYPE"PLUMBING"
HDL_TAP"TRUE";
"B \NAC \NWC"4;
"S \NAC"
BN"7"139;
%"TAP"
"1","(2450,4025)","0","standard","I157";
;
CDS_LIB"standard"
BODY_TYPE"PLUMBING"
HDL_TAP"TRUE";
"B \NAC \NWC"4;
"S \NAC"
BN"9"141;
%"TAP"
"1","(-975,475)","2","standard","I16";
;
CDS_LIB"standard"
BODY_TYPE"PLUMBING"
HDL_TAP"TRUE";
"B \NAC \NWC"10;
"S \NAC"
BN"0"90;
%"SOCKET4677_AZIF0045P001C01CS"
"13","(750,1925)","0","pure_quanta","I168";
;
PART_NUMBER"DGA^7000023"
PART_TYPE"SMLF"
MATERIAL"IO"
VALUE"SOCKET4677_AZIF0045-P001C01CS"
$LOCATION"U1"
CDS_LIB"pure_quanta"
NEEDS_NO_SIZE"TRUE"
CDS_LMAN_SYM_OUTLINE"-1100,2250,1050,-2250"
CDS_LOCATION"U1"
$SEC"13"
CDS_SEC"13";
"DDR5_SB_PAR"
$PN"EJ39"99;
"DDR5_SB_ECC0"
$PN"ED32"98;
"DDR5_SB_ECC1"
$PN"EE31"97;
"DDR5_SB_ECC2"
$PN"EH32"96;
"DDR5_SB_ECC3"
$PN"EG31"95;
"DDR5_SB_ECC4"
$PN"EE35"94;
"DDR5_SB_ECC5"
$PN"ED34"93;
"DDR5_SB_ECC6"
$PN"EG35"92;
"DDR5_SB_ECC7"
$PN"EH34"91;
"DDR5_SB_DQS_DP0"
$PN"DT30"100;
"DDR5_SB_DQS_DP1"
$PN"EC21"101;
"DDR5_SB_DQS_DP2"
$PN"EK12"102;
"DDR5_SB_DQS_DP3"
$PN"DV18"103;
"DDR5_SB_DQS_DP4"
$PN"EG33"104;
"DDR5_SB_DQS_DP5"
$PN"DY30"105;
"DDR5_SB_DQS_DP6"
$PN"EG21"106;
"DDR5_SB_DQS_DP7"
$PN"EP12"107;
"DDR5_SB_DQS_DP8"
$PN"EB18"108;
"DDR5_SB_DQS_DP9"
$PN"EC33"109;
"DDR5_SB_DQS_DN0 \B"
$PN"DV30"110;
"DDR5_SB_DQS_DN1 \B"
$PN"EE21"111;
"DDR5_SB_DQS_DN2 \B"
$PN"EM12"112;
"DDR5_SB_DQS_DN3 \B"
$PN"DT18"113;
"DDR5_SB_DQS_DN4 \B"
$PN"EJ33"114;
"DDR5_SB_DQS_DN5 \B"
$PN"EB30"115;
"DDR5_SB_DQS_DN6 \B"
$PN"EJ21"116;
"DDR5_SB_DQS_DN7 \B"
$PN"ET12"117;
"DDR5_SB_DQS_DN8 \B"
$PN"DY18"118;
"DDR5_SB_DQS_DN9 \B"
$PN"EE33"119;
"DDR5_SB_DQ0"
$PN"DV32"90;
"DDR5_SB_DQ1"
$PN"DU31"89;
"DDR5_SB_DQ2"
$PN"DY32"88;
"DDR5_SB_DQ3"
$PN"EA31"87;
"DDR5_SB_DQ4"
$PN"DU29"86;
"DDR5_SB_DQ5"
$PN"DV28"85;
"DDR5_SB_DQ6"
$PN"EA29"84;
"DDR5_SB_DQ7"
$PN"DY28"83;
"DDR5_SB_DQ8"
$PN"EE23"82;
"DDR5_SB_DQ9"
$PN"ED22"81;
"DDR5_SB_DQ10"
$PN"EG23"80;
"DDR5_SB_DQ11"
$PN"EH22"15;
"DDR5_SB_DQ12"
$PN"ED20"79;
"DDR5_SB_DQ13"
$PN"EE19"78;
"DDR5_SB_DQ14"
$PN"EH20"77;
"DDR5_SB_DQ15"
$PN"EG19"76;
"DDR5_SB_DQ16"
$PN"EM14"75;
"DDR5_SB_DQ17"
$PN"EL13"74;
"DDR5_SB_DQ18"
$PN"EP14"73;
"DDR5_SB_DQ19"
$PN"ER13"72;
"DDR5_SB_DQ20"
$PN"EL11"71;
"DDR5_SB_DQ21"
$PN"EM10"70;
"DDR5_SB_DQ22"
$PN"ER11"69;
"DDR5_SB_DQ23"
$PN"EP10"68;
"DDR5_SB_DQ24"
$PN"DV20"67;
"DDR5_SB_DQ25"
$PN"DU19"66;
"DDR5_SB_DQ26"
$PN"DY20"65;
"DDR5_SB_DQ27"
$PN"EA19"64;
"DDR5_SB_DQ28"
$PN"EA17"63;
"DDR5_SB_DQ29"
$PN"DU17"62;
"DDR5_SB_DQ30"
$PN"EC17"61;
"DDR5_SB_DQ31"
$PN"DR17"60;
"DDR5_SB_CS_N0 \B"
$PN"EH38"120;
"DDR5_SB_CS_N1 \B"
$PN"EG37"121;
"DDR5_SB_CS_N2 \B"
$PN"ED38"122;
"DDR5_SB_CS_N3 \B"
$PN"EE37"123;
"DDR5_SB_CA0"
$PN"DV51"124;
"DDR5_SB_CA1"
$PN"DU50"125;
"DDR5_SB_CA2"
$PN"EE41"126;
"DDR5_SB_CA3"
$PN"EG41"127;
"DDR5_SB_CA4"
$PN"ED40"128;
"DDR5_SB_CA5"
$PN"EH40"129;
"DDR5_SB_CA6"
$PN"EC39"130;
"DDR5_SA_PAR"
$PN"EA50"131;
"DDR5_SA_ECC0"
$PN"EE60"59;
"DDR5_SA_ECC1"
$PN"ED59"58;
"DDR5_SA_ECC2"
$PN"EG60"57;
"DDR5_SA_ECC3"
$PN"EH59"56;
"DDR5_SA_ECC4"
$PN"ED57"55;
"DDR5_SA_ECC5"
$PN"EE56"54;
"DDR5_SA_ECC6"
$PN"EH57"53;
"DDR5_SA_ECC7"
$PN"EG56"16;
"DDR5_SA_DQS_DP0"
$PN"EC76"132;
"DDR5_SA_DQS_DP1"
$PN"DV67"133;
"DDR5_SA_DQS_DP2"
$PN"EE64"134;
"DDR5_SA_DQS_DP3"
$PN"DT55"135;
"DDR5_SA_DQS_DP4"
$PN"EC58"136;
"DDR5_SA_DQS_DP5"
$PN"EG76"137;
"DDR5_SA_DQS_DP6"
$PN"DY67"138;
"DDR5_SA_DQS_DP7"
$PN"EG64"139;
"DDR5_SA_DQS_DP8"
$PN"DY55"140;
"DDR5_SA_DQS_DP9"
$PN"EG58"141;
"DDR5_SA_DQS_DN0 \B"
$PN"EE76"142;
"DDR5_SA_DQS_DN1 \B"
$PN"DT67"143;
"DDR5_SA_DQS_DN2 \B"
$PN"EC64"144;
"DDR5_SA_DQS_DN3 \B"
$PN"DV55"145;
"DDR5_SA_DQS_DN4 \B"
$PN"EE58"146;
"DDR5_SA_DQS_DN5 \B"
$PN"EJ76"147;
"DDR5_SA_DQS_DN6 \B"
$PN"EB67"148;
"DDR5_SA_DQS_DN7 \B"
$PN"EJ64"149;
"DDR5_SA_DQS_DN8 \B"
$PN"EB55"150;
"DDR5_SA_DQS_DN9 \B"
$PN"EJ58"151;
"DDR5_SA_DQ0"
$PN"EB77"17;
"DDR5_SA_DQ1"
$PN"EH77"18;
"DDR5_SA_DQ2"
$PN"ED77"19;
"DDR5_SA_DQ3"
$PN"EG78"52;
"DDR5_SA_DQ4"
$PN"ED75"51;
"DDR5_SA_DQ5"
$PN"EE74"50;
"DDR5_SA_DQ6"
$PN"EH75"49;
"DDR5_SA_DQ7"
$PN"EG74"48;
"DDR5_SA_DQ8"
$PN"DV69"47;
"DDR5_SA_DQ9"
$PN"DU68"46;
"DDR5_SA_DQ10"
$PN"DY69"45;
"DDR5_SA_DQ11"
$PN"EA68"44;
"DDR5_SA_DQ12"
$PN"DU66"43;
"DDR5_SA_DQ13"
$PN"DV65"42;
"DDR5_SA_DQ14"
$PN"EA66"41;
"DDR5_SA_DQ15"
$PN"DY65"40;
"DDR5_SA_DQ16"
$PN"EE66"39;
"DDR5_SA_DQ17"
$PN"ED65"38;
"DDR5_SA_DQ18"
$PN"EG66"37;
"DDR5_SA_DQ19"
$PN"EH65"36;
"DDR5_SA_DQ20"
$PN"ED63"35;
"DDR5_SA_DQ21"
$PN"EE62"34;
"DDR5_SA_DQ22"
$PN"EH63"33;
"DDR5_SA_DQ23"
$PN"EG62"32;
"DDR5_SA_DQ24"
$PN"DV57"31;
"DDR5_SA_DQ25"
$PN"DU56"30;
"DDR5_SA_DQ26"
$PN"DY57"29;
"DDR5_SA_DQ27"
$PN"EA56"28;
"DDR5_SA_DQ28"
$PN"DU54"27;
"DDR5_SA_DQ29"
$PN"DV53"26;
"DDR5_SA_DQ30"
$PN"EA54"25;
"DDR5_SA_DQ31"
$PN"DY53"24;
"DDR5_SA_CS_N0 \B"
$PN"EG54"152;
"DDR5_SA_CS_N1 \B"
$PN"EH53"153;
"DDR5_SA_CS_N2 \B"
$PN"EE54"154;
"DDR5_SA_CS_N3 \B"
$PN"ED53"155;
"DDR5_SA_CA0"
$PN"EC52"156;
"DDR5_SA_CA1"
$PN"EJ52"157;
"DDR5_SA_CA2"
$PN"ED51"158;
"DDR5_SA_CA3"
$PN"EH51"159;
"DDR5_SA_CA4"
$PN"EE50"160;
"DDR5_SA_CA5"
$PN"EG50"161;
"DDR5_SA_CA6"
$PN"DY51"162;
"DDR5_CLK_DP0"
$PN"EB49"23;
"DDR5_CLK_DP1"
$PN"DT49"22;
"DDR5_CLK_DN0 \B"
$PN"DY49"21;
"DDR5_CLK_DN1 \B"
$PN"DV49"20;
"DDR5_B_RSP0"
$PN"DL48"163;
"DDR5_B_RSP1"
$PN"DK47"164;
"DDR5_A_RSP0"
$PN"DN48"165;
"DDR5_A_RSP1"
$PN"DP47"166;
"DDR5_ALERT_N \B"
$PN"CW48"167;
%"TAP"
"1","(-975,425)","2","standard","I17";
;
CDS_LIB"standard"
BODY_TYPE"PLUMBING"
HDL_TAP"TRUE";
"B \NAC \NWC"9;
"S \NAC"
BN"7"91;
%"TAP"
"1","(-975,525)","2","standard","I18";
;
CDS_LIB"standard"
BODY_TYPE"PLUMBING"
HDL_TAP"TRUE";
"B \NAC \NWC"10;
"S \NAC"
BN"1"89;
%"TAP"
"1","(-975,625)","2","standard","I19";
;
CDS_LIB"standard"
BODY_TYPE"PLUMBING"
HDL_TAP"TRUE";
"B \NAC \NWC"10;
"S \NAC"
BN"3"87;
%"TAP"
"1","(-975,575)","2","standard","I20";
;
CDS_LIB"standard"
BODY_TYPE"PLUMBING"
HDL_TAP"TRUE";
"B \NAC \NWC"10;
"S \NAC"
BN"2"88;
%"TAP"
"1","(-975,675)","2","standard","I21";
;
CDS_LIB"standard"
BODY_TYPE"PLUMBING"
HDL_TAP"TRUE";
"B \NAC \NWC"10;
"S \NAC"
BN"4"86;
%"TAP"
"1","(-975,775)","2","standard","I22";
;
CDS_LIB"standard"
BODY_TYPE"PLUMBING"
HDL_TAP"TRUE";
"B \NAC \NWC"10;
"S \NAC"
BN"6"84;
%"TAP"
"1","(-975,725)","2","standard","I23";
;
CDS_LIB"standard"
BODY_TYPE"PLUMBING"
HDL_TAP"TRUE";
"B \NAC \NWC"10;
"S \NAC"
BN"5"85;
%"TAP"
"1","(-975,875)","2","standard","I24";
;
CDS_LIB"standard"
BODY_TYPE"PLUMBING"
HDL_TAP"TRUE";
"B \NAC \NWC"10;
"S \NAC"
BN"8"82;
%"TAP"
"1","(-975,825)","2","standard","I25";
;
CDS_LIB"standard"
BODY_TYPE"PLUMBING"
HDL_TAP"TRUE";
"B \NAC \NWC"10;
"S \NAC"
BN"7"83;
%"TAP"
"1","(-975,925)","2","standard","I26";
;
CDS_LIB"standard"
BODY_TYPE"PLUMBING"
HDL_TAP"TRUE";
"B \NAC \NWC"10;
"S \NAC"
BN"9"81;
%"TAP"
"1","(-975,975)","2","standard","I27";
;
CDS_LIB"standard"
BODY_TYPE"PLUMBING"
HDL_TAP"TRUE";
"B \NAC \NWC"10;
"S \NAC"
BN"10"80;
%"TAP"
"1","(-975,1025)","2","standard","I28";
;
CDS_LIB"standard"
BODY_TYPE"PLUMBING"
HDL_TAP"TRUE";
"B \NAC \NWC"10;
"S \NAC"
BN"11"15;
%"TAP"
"1","(-975,1125)","2","standard","I29";
;
CDS_LIB"standard"
BODY_TYPE"PLUMBING"
HDL_TAP"TRUE";
"B \NAC \NWC"10;
"S \NAC"
BN"13"78;
%"TAP"
"1","(-975,-125)","2","standard","I3";
;
CDS_LIB"standard"
BODY_TYPE"PLUMBING"
HDL_TAP"TRUE";
"B \NAC \NWC"14;
"S \NAC"
BN"1"20;
%"TAP"
"1","(-975,1075)","2","standard","I30";
;
CDS_LIB"standard"
BODY_TYPE"PLUMBING"
HDL_TAP"TRUE";
"B \NAC \NWC"10;
"S \NAC"
BN"12"79;
%"TAP"
"1","(-975,1175)","2","standard","I31";
;
CDS_LIB"standard"
BODY_TYPE"PLUMBING"
HDL_TAP"TRUE";
"B \NAC \NWC"10;
"S \NAC"
BN"14"77;
%"TAP"
"1","(-975,1225)","2","standard","I32";
;
CDS_LIB"standard"
BODY_TYPE"PLUMBING"
HDL_TAP"TRUE";
"B \NAC \NWC"10;
"S \NAC"
BN"15"76;
%"TAP"
"1","(-975,1275)","2","standard","I33";
;
CDS_LIB"standard"
BODY_TYPE"PLUMBING"
HDL_TAP"TRUE";
"B \NAC \NWC"10;
"S \NAC"
BN"16"75;
%"TAP"
"1","(-975,1375)","2","standard","I34";
;
CDS_LIB"standard"
BODY_TYPE"PLUMBING"
HDL_TAP"TRUE";
"B \NAC \NWC"10;
"S \NAC"
BN"18"73;
%"TAP"
"1","(-975,1425)","2","standard","I35";
;
CDS_LIB"standard"
BODY_TYPE"PLUMBING"
HDL_TAP"TRUE";
"B \NAC \NWC"10;
"S \NAC"
BN"19"72;
%"TAP"
"1","(-975,1325)","2","standard","I36";
;
CDS_LIB"standard"
BODY_TYPE"PLUMBING"
HDL_TAP"TRUE";
"B \NAC \NWC"10;
"S \NAC"
BN"17"74;
%"TAP"
"1","(-975,1525)","2","standard","I37";
;
CDS_LIB"standard"
BODY_TYPE"PLUMBING"
HDL_TAP"TRUE";
"B \NAC \NWC"10;
"S \NAC"
BN"21"70;
%"TAP"
"1","(-975,1475)","2","standard","I38";
;
CDS_LIB"standard"
BODY_TYPE"PLUMBING"
HDL_TAP"TRUE";
"B \NAC \NWC"10;
"S \NAC"
BN"20"71;
%"TAP"
"1","(-975,1575)","2","standard","I39";
;
CDS_LIB"standard"
BODY_TYPE"PLUMBING"
HDL_TAP"TRUE";
"B \NAC \NWC"10;
"S \NAC"
BN"22"69;
%"TAP"
"1","(-975,-175)","2","standard","I4";
;
CDS_LIB"standard"
BODY_TYPE"PLUMBING"
HDL_TAP"TRUE";
"B \NAC \NWC"14;
"S \NAC"
BN"0"21;
%"TAP"
"1","(-975,1625)","2","standard","I40";
;
CDS_LIB"standard"
BODY_TYPE"PLUMBING"
HDL_TAP"TRUE";
"B \NAC \NWC"10;
"S \NAC"
BN"23"68;
%"TAP"
"1","(-975,1675)","2","standard","I41";
;
CDS_LIB"standard"
BODY_TYPE"PLUMBING"
HDL_TAP"TRUE";
"B \NAC \NWC"10;
"S \NAC"
BN"24"67;
%"TAP"
"1","(-975,1725)","2","standard","I42";
;
CDS_LIB"standard"
BODY_TYPE"PLUMBING"
HDL_TAP"TRUE";
"B \NAC \NWC"10;
"S \NAC"
BN"25"66;
%"TAP"
"1","(-975,1775)","2","standard","I43";
;
CDS_LIB"standard"
BODY_TYPE"PLUMBING"
HDL_TAP"TRUE";
"B \NAC \NWC"10;
"S \NAC"
BN"26"65;
%"TAP"
"1","(-975,1825)","2","standard","I44";
;
CDS_LIB"standard"
BODY_TYPE"PLUMBING"
HDL_TAP"TRUE";
"B \NAC \NWC"10;
"S \NAC"
BN"27"64;
%"TAP"
"1","(-975,1875)","2","standard","I45";
;
CDS_LIB"standard"
BODY_TYPE"PLUMBING"
HDL_TAP"TRUE";
"B \NAC \NWC"10;
"S \NAC"
BN"28"63;
%"TAP"
"1","(-975,1925)","2","standard","I46";
;
CDS_LIB"standard"
BODY_TYPE"PLUMBING"
HDL_TAP"TRUE";
"B \NAC \NWC"10;
"S \NAC"
BN"29"62;
%"TAP"
"1","(-975,2025)","2","standard","I47";
;
CDS_LIB"standard"
BODY_TYPE"PLUMBING"
HDL_TAP"TRUE";
"B \NAC \NWC"10;
"S \NAC"
BN"31"60;
%"TAP"
"1","(-975,1975)","2","standard","I48";
;
CDS_LIB"standard"
BODY_TYPE"PLUMBING"
HDL_TAP"TRUE";
"B \NAC \NWC"10;
"S \NAC"
BN"30"61;
%"TAP"
"1","(-975,2175)","2","standard","I49";
;
CDS_LIB"standard"
BODY_TYPE"PLUMBING"
HDL_TAP"TRUE";
"B \NAC \NWC"11;
"S \NAC"
BN"2"57;
%"TAP"
"1","(-975,125)","2","standard","I5";
;
CDS_LIB"standard"
BODY_TYPE"PLUMBING"
HDL_TAP"TRUE";
"B \NAC \NWC"9;
"S \NAC"
BN"1"97;
%"TAP"
"1","(-975,2125)","2","standard","I50";
;
CDS_LIB"standard"
BODY_TYPE"PLUMBING"
HDL_TAP"TRUE";
"B \NAC \NWC"11;
"S \NAC"
BN"1"58;
%"TAP"
"1","(-975,2075)","2","standard","I51";
;
CDS_LIB"standard"
BODY_TYPE"PLUMBING"
HDL_TAP"TRUE";
"B \NAC \NWC"11;
"S \NAC"
BN"0"59;
%"TAP"
"1","(-975,2275)","2","standard","I54";
;
CDS_LIB"standard"
BODY_TYPE"PLUMBING"
HDL_TAP"TRUE";
"B \NAC \NWC"11;
"S \NAC"
BN"4"55;
%"TAP"
"1","(-975,2325)","2","standard","I55";
;
CDS_LIB"standard"
BODY_TYPE"PLUMBING"
HDL_TAP"TRUE";
"B \NAC \NWC"11;
"S \NAC"
BN"5"54;
%"TAP"
"1","(-975,2225)","2","standard","I56";
;
CDS_LIB"standard"
BODY_TYPE"PLUMBING"
HDL_TAP"TRUE";
"B \NAC \NWC"11;
"S \NAC"
BN"3"56;
%"TAP"
"1","(-975,2425)","2","standard","I57";
;
CDS_LIB"standard"
BODY_TYPE"PLUMBING"
HDL_TAP"TRUE";
"B \NAC \NWC"11;
"S \NAC"
BN"7"16;
%"TAP"
"1","(-975,2375)","2","standard","I58";
;
CDS_LIB"standard"
BODY_TYPE"PLUMBING"
HDL_TAP"TRUE";
"B \NAC \NWC"11;
"S \NAC"
BN"6"53;
%"TAP"
"1","(-975,2525)","2","standard","I59";
;
CDS_LIB"standard"
BODY_TYPE"PLUMBING"
HDL_TAP"TRUE";
"B \NAC \NWC"12;
"S \NAC"
BN"1"18;
%"TAP"
"1","(-975,75)","2","standard","I6";
;
CDS_LIB"standard"
BODY_TYPE"PLUMBING"
HDL_TAP"TRUE";
"B \NAC \NWC"9;
"S \NAC"
BN"0"98;
%"TAP"
"1","(-975,2475)","2","standard","I60";
;
CDS_LIB"standard"
BODY_TYPE"PLUMBING"
HDL_TAP"TRUE";
"B \NAC \NWC"12;
"S \NAC"
BN"0"17;
%"TAP"
"1","(-975,2575)","2","standard","I61";
;
CDS_LIB"standard"
BODY_TYPE"PLUMBING"
HDL_TAP"TRUE";
"B \NAC \NWC"12;
"S \NAC"
BN"2"19;
%"TAP"
"1","(-975,2675)","2","standard","I62";
;
CDS_LIB"standard"
BODY_TYPE"PLUMBING"
HDL_TAP"TRUE";
"B \NAC \NWC"12;
"S \NAC"
BN"4"51;
%"TAP"
"1","(-975,2625)","2","standard","I63";
;
CDS_LIB"standard"
BODY_TYPE"PLUMBING"
HDL_TAP"TRUE";
"B \NAC \NWC"12;
"S \NAC"
BN"3"52;
%"TAP"
"1","(-975,2725)","2","standard","I64";
;
CDS_LIB"standard"
BODY_TYPE"PLUMBING"
HDL_TAP"TRUE";
"B \NAC \NWC"12;
"S \NAC"
BN"5"50;
%"TAP"
"1","(-975,2825)","2","standard","I65";
;
CDS_LIB"standard"
BODY_TYPE"PLUMBING"
HDL_TAP"TRUE";
"B \NAC \NWC"12;
"S \NAC"
BN"7"48;
%"TAP"
"1","(-975,2775)","2","standard","I66";
;
CDS_LIB"standard"
BODY_TYPE"PLUMBING"
HDL_TAP"TRUE";
"B \NAC \NWC"12;
"S \NAC"
BN"6"49;
%"TAP"
"1","(-975,2925)","2","standard","I67";
;
CDS_LIB"standard"
BODY_TYPE"PLUMBING"
HDL_TAP"TRUE";
"B \NAC \NWC"12;
"S \NAC"
BN"9"46;
%"TAP"
"1","(-975,2875)","2","standard","I68";
;
CDS_LIB"standard"
BODY_TYPE"PLUMBING"
HDL_TAP"TRUE";
"B \NAC \NWC"12;
"S \NAC"
BN"8"47;
%"TAP"
"1","(-975,2975)","2","standard","I69";
;
CDS_LIB"standard"
BODY_TYPE"PLUMBING"
HDL_TAP"TRUE";
"B \NAC \NWC"12;
"S \NAC"
BN"10"45;
%"TAP"
"1","(-975,-75)","2","standard","I7";
;
CDS_LIB"standard"
BODY_TYPE"PLUMBING"
HDL_TAP"TRUE";
"B \NAC \NWC"13;
"S \NAC"
BN"0"23;
%"TAP"
"1","(-975,3025)","2","standard","I70";
;
CDS_LIB"standard"
BODY_TYPE"PLUMBING"
HDL_TAP"TRUE";
"B \NAC \NWC"12;
"S \NAC"
BN"11"44;
%"TAP"
"1","(-975,3075)","2","standard","I71";
;
CDS_LIB"standard"
BODY_TYPE"PLUMBING"
HDL_TAP"TRUE";
"B \NAC \NWC"12;
"S \NAC"
BN"12"43;
%"TAP"
"1","(-975,3175)","2","standard","I72";
;
CDS_LIB"standard"
BODY_TYPE"PLUMBING"
HDL_TAP"TRUE";
"B \NAC \NWC"12;
"S \NAC"
BN"14"41;
%"TAP"
"1","(-975,3125)","2","standard","I73";
;
CDS_LIB"standard"
BODY_TYPE"PLUMBING"
HDL_TAP"TRUE";
"B \NAC \NWC"12;
"S \NAC"
BN"13"42;
%"TAP"
"1","(-975,3225)","2","standard","I74";
;
CDS_LIB"standard"
BODY_TYPE"PLUMBING"
HDL_TAP"TRUE";
"B \NAC \NWC"12;
"S \NAC"
BN"15"40;
%"TAP"
"1","(-975,3275)","2","standard","I75";
;
CDS_LIB"standard"
BODY_TYPE"PLUMBING"
HDL_TAP"TRUE";
"B \NAC \NWC"12;
"S \NAC"
BN"16"39;
%"TAP"
"1","(-975,3325)","2","standard","I76";
;
CDS_LIB"standard"
BODY_TYPE"PLUMBING"
HDL_TAP"TRUE";
"B \NAC \NWC"12;
"S \NAC"
BN"17"38;
%"TAP"
"1","(-975,3425)","2","standard","I77";
;
CDS_LIB"standard"
BODY_TYPE"PLUMBING"
HDL_TAP"TRUE";
"B \NAC \NWC"12;
"S \NAC"
BN"19"36;
%"TAP"
"1","(-975,3475)","2","standard","I78";
;
CDS_LIB"standard"
BODY_TYPE"PLUMBING"
HDL_TAP"TRUE";
"B \NAC \NWC"12;
"S \NAC"
BN"20"35;
%"TAP"
"1","(-975,3375)","2","standard","I79";
;
CDS_LIB"standard"
BODY_TYPE"PLUMBING"
HDL_TAP"TRUE";
"B \NAC \NWC"12;
"S \NAC"
BN"18"37;
%"TAP"
"1","(-975,-25)","2","standard","I8";
;
CDS_LIB"standard"
BODY_TYPE"PLUMBING"
HDL_TAP"TRUE";
"B \NAC \NWC"13;
"S \NAC"
BN"1"22;
%"TAP"
"1","(-975,3575)","2","standard","I80";
;
CDS_LIB"standard"
BODY_TYPE"PLUMBING"
HDL_TAP"TRUE";
"B \NAC \NWC"12;
"S \NAC"
BN"22"33;
%"TAP"
"1","(-975,3525)","2","standard","I81";
;
CDS_LIB"standard"
BODY_TYPE"PLUMBING"
HDL_TAP"TRUE";
"B \NAC \NWC"12;
"S \NAC"
BN"21"34;
%"TAP"
"1","(-975,3675)","2","standard","I82";
;
CDS_LIB"standard"
BODY_TYPE"PLUMBING"
HDL_TAP"TRUE";
"B \NAC \NWC"12;
"S \NAC"
BN"24"31;
%"TAP"
"1","(-975,3625)","2","standard","I83";
;
CDS_LIB"standard"
BODY_TYPE"PLUMBING"
HDL_TAP"TRUE";
"B \NAC \NWC"12;
"S \NAC"
BN"23"32;
%"TAP"
"1","(-975,3725)","2","standard","I84";
;
CDS_LIB"standard"
BODY_TYPE"PLUMBING"
HDL_TAP"TRUE";
"B \NAC \NWC"12;
"S \NAC"
BN"25"30;
%"TAP"
"1","(-975,3825)","2","standard","I85";
;
CDS_LIB"standard"
BODY_TYPE"PLUMBING"
HDL_TAP"TRUE";
"B \NAC \NWC"12;
"S \NAC"
BN"27"28;
%"TAP"
"1","(-975,3775)","2","standard","I86";
;
CDS_LIB"standard"
BODY_TYPE"PLUMBING"
HDL_TAP"TRUE";
"B \NAC \NWC"12;
"S \NAC"
BN"26"29;
%"TAP"
"1","(-975,3875)","2","standard","I87";
;
CDS_LIB"standard"
BODY_TYPE"PLUMBING"
HDL_TAP"TRUE";
"B \NAC \NWC"12;
"S \NAC"
BN"28"27;
%"TAP"
"1","(-975,3925)","2","standard","I88";
;
CDS_LIB"standard"
BODY_TYPE"PLUMBING"
HDL_TAP"TRUE";
"B \NAC \NWC"12;
"S \NAC"
BN"29"26;
%"TAP"
"1","(-975,3975)","2","standard","I89";
;
CDS_LIB"standard"
BODY_TYPE"PLUMBING"
HDL_TAP"TRUE";
"B \NAC \NWC"12;
"S \NAC"
BN"30"25;
%"TAP"
"1","(-975,175)","2","standard","I9";
;
CDS_LIB"standard"
BODY_TYPE"PLUMBING"
HDL_TAP"TRUE";
"B \NAC \NWC"9;
"S \NAC"
BN"2"96;
%"TAP"
"1","(-975,4025)","2","standard","I90";
;
CDS_LIB"standard"
BODY_TYPE"PLUMBING"
HDL_TAP"TRUE";
"B \NAC \NWC"12;
"S \NAC"
BN"31"24;
%"TAP"
"1","(2450,275)","0","standard","I96";
;
CDS_LIB"standard"
BODY_TYPE"PLUMBING"
HDL_TAP"TRUE";
"B \NAC \NWC"6;
"S \NAC"
BN"0"120;
%"TAP"
"1","(2450,425)","0","standard","I97";
;
CDS_LIB"standard"
BODY_TYPE"PLUMBING"
HDL_TAP"TRUE";
"B \NAC \NWC"6;
"S \NAC"
BN"3"123;
%"TAP"
"1","(2450,325)","0","standard","I98";
;
CDS_LIB"standard"
BODY_TYPE"PLUMBING"
HDL_TAP"TRUE";
"B \NAC \NWC"6;
"S \NAC"
BN"1"121;
%"TAP"
"1","(2450,375)","0","standard","I99";
;
CDS_LIB"standard"
BODY_TYPE"PLUMBING"
HDL_TAP"TRUE";
"B \NAC \NWC"6;
"S \NAC"
BN"2"122;
END.
